# BASEBOARD_FAB2 (Tioga Pass) — schematic netlist excerpt (pin names and nets, part order shuffled) for the footprints in the layout excerpt that follows; sources: Cadence DE-HDL packaged netlist, KiCad conversion of Wiwynn_Tioga_Pass_MB.brd

C2L17  CAP_A  0.01UF 25V 10% X7R  pkg 0402V  page 173 : A = SATA6G_PCH_PCIE_UP_SATA_RXN<0> ; B = SATA6G_P0_RX_C_DN
C2M23  CAP_A  0.1UF 16V 10% X7R  pkg 0402V  page 139 : A = PE_PCH_SPRV_TX_DP ; B = PE_PCH_SPRV_TX_C_DP
C9G17  CAP  47.0PF 50V 5% COG  pkg 0402LF  page 169 : A = A_P12V_STBY_SCALED ; B = GND

(kicad_pcb
	(version 20260206)
	(generator "pcbnew")
	(generator_version "10.0")
	(general
		(thickness 1.6)
		(legacy_teardrops no)
	)
	(paper "A4")
	(title_block
		(title "Wiwynn_Tioga_Pass_MB.brd")
		(comment 1 "Tioga Pass / footprints 2858-2860 of 4770")
	)
	(layers
		(0 "F.Cu" signal "TOP")
		(4 "In1.Cu" signal "L2GND")
		(6 "In2.Cu" signal "L3")
		(8 "In3.Cu" signal "L4GND")
		(10 "In4.Cu" signal "L5")
		(12 "In5.Cu" signal "L6GND")
		(14 "In6.Cu" signal "L7VCC")
		(16 "In7.Cu" signal "L8VCC")
		(18 "In8.Cu" signal "L9GND")
		(20 "In9.Cu" signal "L10")
		(22 "In10.Cu" signal "L11GND")
		(24 "In11.Cu" signal "L12")
		(26 "In12.Cu" signal "L13GND")
		(2 "B.Cu" signal "BOTTOM")
		(9 "F.Adhes" user "F.Adhesive")
		(11 "B.Adhes" user "B.Adhesive")
		(13 "F.Paste" user "Package Geometry/Pastemask Top")
		(15 "B.Paste" user "Package Geometry/Pastemask Bottom")
		(5 "F.SilkS" user "Ref Des/Silkscreen Top")
		(7 "B.SilkS" user "Ref Des/Silkscreen Bottom")
		(1 "F.Mask" user "Board Geometry/Soldermask Top")
		(3 "B.Mask" user "Board Geometry/Soldermask Bottom")
		(17 "Dwgs.User" user "User.Drawings")
		(19 "Cmts.User" user "User.Comments")
		(21 "Eco1.User" user "User.Eco1")
		(23 "Eco2.User" user "User.Eco2")
		(25 "Edge.Cuts" user "Board Geometry/Outline")
		(27 "Margin" user)
		(31 "F.CrtYd" user "Package Geometry/Place Bound Top")
		(29 "B.CrtYd" user "Package Geometry/Place Bound Bottom")
		(35 "F.Fab" user "Ref Des/Assembly Top")
		(33 "B.Fab" user "Ref Des/Assembly Bottom")
	)
	(footprint ""
		(layer "B.Cu")
		(at 401.992846 -27.124152)
		(property "Reference" "C9G17"
			(at 0 0 0)
			(layer "B.SilkS")
			(hide yes)
			(effects
				(font
					(size 1.27 1.27)
				)
				(justify mirror)
			)
		)
		(property "Value" ""
			(at 0 0 0)
			(layer "B.Fab")
			(effects
				(font
					(size 1.27 1.27)
				)
				(justify mirror)
			)
		)
		(duplicate_pad_numbers_are_jumpers no)
		(fp_poly
			(pts
				(xy -0.3048 -0.1016) (xy -0.3048 0.9906) (xy 0.3048 0.9906) (xy 0.3048 -0.1016)
			)
			(stroke
				(width 0)
				(type default)
			)
			(fill no)
			(layer "B.CrtYd")
		)
		(fp_line
			(start -0.3048 -0.1016)
			(end 0.3048 -0.1016)
			(stroke
				(width 0.1)
				(type default)
			)
			(layer "B.Fab")
		)
		(fp_line
			(start -0.3048 0.9906)
			(end -0.3048 -0.1016)
			(stroke
				(width 0.1)
				(type default)
			)
			(layer "B.Fab")
		)
		(fp_line
			(start 0.3048 -0.1016)
			(end 0.3048 0.9906)
			(stroke
				(width 0.1)
				(type default)
			)
			(layer "B.Fab")
		)
		(fp_line
			(start 0.3048 0.9906)
			(end -0.3048 0.9906)
			(stroke
				(width 0.1)
				(type default)
			)
			(layer "B.Fab")
		)
		(pad "1" smd rect
			(at 0 0 180)
			(size 0.508 0.508)
			(layers "B.Cu" "B.Mask" "B.Paste")
			(net "A_P12V_STBY_SCALED")
		)
		(pad "2" smd rect
			(at 0 0.889 180)
			(size 0.508 0.508)
			(layers "B.Cu" "B.Mask" "B.Paste")
			(net "GND")
		)
		(zone
			(layer "B.Cu")
			(hatch none 0.5)
			(connect_pads
				(clearance 0)
			)
			(min_thickness 0.25)
			(keepout
				(tracks allowed)
				(vias not_allowed)
				(pads allowed)
				(copperpour not_allowed)
				(footprints allowed)
			)
			(placement
				(enabled no)
				(sheetname "")
			)
			(fill
				(thermal_gap 0.5)
				(thermal_bridge_width 0.5)
				(island_removal_mode 0)
			)
			(polygon
				(pts
					(xy 402.246846 -26.870152) (xy 401.738846 -26.870152) (xy 401.738846 -26.489152) (xy 402.246846 -26.489152)
				)
			)
		)
		(zone
			(layer "B.Cu")
			(hatch none 0.5)
			(connect_pads
				(clearance 0)
			)
			(min_thickness 0.25)
			(keepout
				(tracks not_allowed)
				(vias allowed)
				(pads allowed)
				(copperpour not_allowed)
				(footprints allowed)
			)
			(placement
				(enabled no)
				(sheetname "")
			)
			(fill
				(thermal_gap 0.5)
				(thermal_bridge_width 0.5)
				(island_removal_mode 0)
			)
			(polygon
				(pts
					(xy 402.246846 -26.489152) (xy 401.738846 -26.489152) (xy 401.738846 -26.870152) (xy 402.246846 -26.870152)
				)
			)
		)
	)
	(footprint ""
		(layer "B.Cu")
		(at 401.25777 -127.659384 90)
		(property "Reference" "C2M23"
			(at 0 0 90)
			(layer "B.SilkS")
			(hide yes)
			(effects
				(font
					(size 1.27 1.27)
				)
				(justify mirror)
			)
		)
		(property "Value" ""
			(at 0 0 90)
			(layer "B.Fab")
			(effects
				(font
					(size 1.27 1.27)
				)
				(justify mirror)
			)
		)
		(duplicate_pad_numbers_are_jumpers no)
		(fp_poly
			(pts
				(xy -0.3048 -0.1016) (xy -0.3048 0.9906) (xy 0.3048 0.9906) (xy 0.3048 -0.1016)
			)
			(stroke
				(width 0)
				(type default)
			)
			(fill no)
			(layer "B.CrtYd")
		)
		(fp_line
			(start 0.3048 -0.1016)
			(end 0.3048 0.9906)
			(stroke
				(width 0.1)
				(type default)
			)
			(layer "B.Fab")
		)
		(fp_line
			(start -0.3048 -0.1016)
			(end 0.3048 -0.1016)
			(stroke
				(width 0.1)
				(type default)
			)
			(layer "B.Fab")
		)
		(fp_line
			(start 0.3048 0.9906)
			(end -0.3048 0.9906)
			(stroke
				(width 0.1)
				(type default)
			)
			(layer "B.Fab")
		)
		(fp_line
			(start -0.3048 0.9906)
			(end -0.3048 -0.1016)
			(stroke
				(width 0.1)
				(type default)
			)
			(layer "B.Fab")
		)
		(pad "1" smd rect
			(at 0 0 270)
			(size 0.508 0.508)
			(layers "B.Cu" "B.Mask" "B.Paste")
			(net "PE_PCH_SPRV_TX_DP")
		)
		(pad "2" smd rect
			(at 0 0.889 270)
			(size 0.508 0.508)
			(layers "B.Cu" "B.Mask" "B.Paste")
			(net "PE_PCH_SPRV_TX_C_DP")
		)
		(zone
			(layer "B.Cu")
			(hatch none 0.5)
			(connect_pads
				(clearance 0)
			)
			(min_thickness 0.25)
			(keepout
				(tracks allowed)
				(vias not_allowed)
				(pads allowed)
				(copperpour not_allowed)
				(footprints allowed)
			)
			(placement
				(enabled no)
				(sheetname "")
			)
			(fill
				(thermal_gap 0.5)
				(thermal_bridge_width 0.5)
				(island_removal_mode 0)
			)
			(polygon
				(pts
					(xy 401.51177 -127.913384) (xy 401.51177 -127.405384) (xy 401.89277 -127.405384) (xy 401.89277 -127.913384)
				)
			)
		)
		(zone
			(layer "B.Cu")
			(hatch none 0.5)
			(connect_pads
				(clearance 0)
			)
			(min_thickness 0.25)
			(keepout
				(tracks not_allowed)
				(vias allowed)
				(pads allowed)
				(copperpour not_allowed)
				(footprints allowed)
			)
			(placement
				(enabled no)
				(sheetname "")
			)
			(fill
				(thermal_gap 0.5)
				(thermal_bridge_width 0.5)
				(island_removal_mode 0)
			)
			(polygon
				(pts
					(xy 401.89277 -127.913384) (xy 401.89277 -127.405384) (xy 401.51177 -127.405384) (xy 401.51177 -127.913384)
				)
			)
		)
	)
	(footprint ""
		(layer "B.Cu")
		(at 422.70172 -149.987 90)
		(property "Reference" "C2L17"
			(at 0 0 90)
			(layer "B.SilkS")
			(hide yes)
			(effects
				(font
					(size 1.27 1.27)
				)
				(justify mirror)
			)
		)
		(property "Value" ""
			(at 0 0 90)
			(layer "B.Fab")
			(effects
				(font
					(size 1.27 1.27)
				)
				(justify mirror)
			)
		)
		(duplicate_pad_numbers_are_jumpers no)
		(fp_poly
			(pts
				(xy -0.3048 -0.1016) (xy -0.3048 0.9906) (xy 0.3048 0.9906) (xy 0.3048 -0.1016)
			)
			(stroke
				(width 0)
				(type default)
			)
			(fill no)
			(layer "B.CrtYd")
		)
		(fp_line
			(start 0.3048 -0.1016)
			(end 0.3048 0.9906)
			(stroke
				(width 0.1)
				(type default)
			)
			(layer "B.Fab")
		)
		(fp_line
			(start -0.3048 -0.1016)
			(end 0.3048 -0.1016)
			(stroke
				(width 0.1)
				(type default)
			)
			(layer "B.Fab")
		)
		(fp_line
			(start 0.3048 0.9906)
			(end -0.3048 0.9906)
			(stroke
				(width 0.1)
				(type default)
			)
			(layer "B.Fab")
		)
		(fp_line
			(start -0.3048 0.9906)
			(end -0.3048 -0.1016)
			(stroke
				(width 0.1)
				(type default)
			)
			(layer "B.Fab")
		)
		(pad "1" smd rect
			(at 0 0 270)
			(size 0.508 0.508)
			(layers "B.Cu" "B.Mask" "B.Paste")
			(net "SATA6G_PCH_PCIE_UP_SATA_RXN<0>")
		)
		(pad "2" smd rect
			(at 0 0.889 270)
			(size 0.508 0.508)
			(layers "B.Cu" "B.Mask" "B.Paste")
			(net "SATA6G_P0_RX_C_DN")
		)
		(zone
			(layer "B.Cu")
			(hatch none 0.5)
			(connect_pads
				(clearance 0)
			)
			(min_thickness 0.25)
			(keepout
				(tracks allowed)
				(vias not_allowed)
				(pads allowed)
				(copperpour not_allowed)
				(footprints allowed)
			)
			(placement
				(enabled no)
				(sheetname "")
			)
			(fill
				(thermal_gap 0.5)
				(thermal_bridge_width 0.5)
				(island_removal_mode 0)
			)
			(polygon
				(pts
					(xy 422.95572 -150.241) (xy 422.95572 -149.733) (xy 423.33672 -149.733) (xy 423.33672 -150.241)
				)
			)
		)
		(zone
			(layer "B.Cu")
			(hatch none 0.5)
			(connect_pads
				(clearance 0)
			)
			(min_thickness 0.25)
			(keepout
				(tracks not_allowed)
				(vias allowed)
				(pads allowed)
				(copperpour not_allowed)
				(footprints allowed)
			)
			(placement
				(enabled no)
				(sheetname "")
			)
			(fill
				(thermal_gap 0.5)
				(thermal_bridge_width 0.5)
				(island_removal_mode 0)
			)
			(polygon
				(pts
					(xy 423.33672 -150.241) (xy 423.33672 -149.733) (xy 422.95572 -149.733) (xy 422.95572 -150.241)
				)
			)
		)
	)
)
